# T6G (Grand Teton) — schematic netlist excerpt (pin names and nets, part order shuffled) for the footprints in the layout excerpt that follows; sources: Cadence DE-HDL packaged netlist, KiCad conversion of 04192023_DAF0TMB3IC0_F0TG_MB_C_brd_V02_OCP.brd

R263  Q_RES  0 5% CHIP  pkg 0402LF  page 82 : A = CPU1_CORETYPE1 ; B = FM_CPU1_CORETYPE1
R8099  Q_RES  100K 1% CHIP  pkg 0402LF  page 147 : A = P3V3_E1S_PWRGD_0_R1 ; B = GND

(kicad_pcb
	(version 20260206)
	(generator "pcbnew")
	(generator_version "10.0")
	(general
		(thickness 1.6)
		(legacy_teardrops no)
	)
	(paper "A4")
	(title_block
		(title "04192023_DAF0TMB3IC0_F0TG_MB_C_brd_V02_OCP.brd")
		(comment 1 "Grand Teton / footprints 1683-1684 of 8354")
	)
	(layers
		(0 "F.Cu" signal "TOP")
		(4 "In1.Cu" signal "GND")
		(6 "In2.Cu" signal "IN1")
		(8 "In3.Cu" signal "GND1")
		(10 "In4.Cu" signal "IN2")
		(12 "In5.Cu" signal "GND2")
		(14 "In6.Cu" signal "IN3")
		(16 "In7.Cu" signal "GND3")
		(18 "In8.Cu" signal "VCC")
		(20 "In9.Cu" signal "VCC1")
		(22 "In10.Cu" signal "GND4")
		(24 "In11.Cu" signal "IN4")
		(26 "In12.Cu" signal "GND5")
		(28 "In13.Cu" signal "IN5")
		(30 "In14.Cu" signal "GND6")
		(32 "In15.Cu" signal "IN6")
		(34 "In16.Cu" signal "GND7")
		(2 "B.Cu" signal "BOTTOM")
		(9 "F.Adhes" user "F.Adhesive")
		(11 "B.Adhes" user "B.Adhesive")
		(13 "F.Paste" user "Package Geometry/Pastemask Top")
		(15 "B.Paste" user "Package Geometry/Pastemask Bottom")
		(5 "F.SilkS" user "Ref Des/Silkscreen Top")
		(7 "B.SilkS" user "Ref Des/Silkscreen Bottom")
		(1 "F.Mask" user "Board Geometry/Soldermask Top")
		(3 "B.Mask" user "Board Geometry/Soldermask Bottom")
		(17 "Dwgs.User" user "User.Drawings")
		(19 "Cmts.User" user "User.Comments")
		(21 "Eco1.User" user "User.Eco1")
		(23 "Eco2.User" user "User.Eco2")
		(25 "Edge.Cuts" user "Board Geometry/Outline")
		(27 "Margin" user)
		(31 "F.CrtYd" user "Package Geometry/Place Bound Top")
		(29 "B.CrtYd" user "Package Geometry/Place Bound Bottom")
		(35 "F.Fab" user "Ref Des/Assembly Top")
		(33 "B.Fab" user "Ref Des/Assembly Bottom")
	)
	(footprint ""
		(layer "F.Cu")
		(at 223.266 -82.804 180)
		(property "Reference" "R8099"
			(at 0 0 180)
			(layer "F.SilkS")
			(hide yes)
			(effects
				(font
					(size 1.27 1.27)
				)
			)
		)
		(property "Value" ""
			(at 0 0 180)
			(layer "F.Fab")
			(effects
				(font
					(size 1.27 1.27)
				)
			)
		)
		(duplicate_pad_numbers_are_jumpers no)
		(fp_line
			(start 0.7874 0.4064)
			(end -0.7874 0.4064)
			(stroke
				(width 0.1524)
				(type default)
			)
			(layer "F.SilkS")
		)
		(fp_line
			(start 0.7874 -0.4064)
			(end 0.7874 0.4064)
			(stroke
				(width 0.1524)
				(type default)
			)
			(layer "F.SilkS")
		)
		(fp_line
			(start -0.7874 0.4064)
			(end -0.7874 -0.4064)
			(stroke
				(width 0.1524)
				(type default)
			)
			(layer "F.SilkS")
		)
		(fp_line
			(start -0.7874 -0.4064)
			(end 0.7874 -0.4064)
			(stroke
				(width 0.1524)
				(type default)
			)
			(layer "F.SilkS")
		)
		(fp_line
			(start 0.67945 0.3048)
			(end 0.120396 0.3048)
			(stroke
				(width 0.1)
				(type default)
			)
			(layer "F.Fab")
		)
		(fp_line
			(start 0.67945 -0.3048)
			(end 0.67945 0.3048)
			(stroke
				(width 0.1)
				(type default)
			)
			(layer "F.Fab")
		)
		(fp_line
			(start 0.12065 -0.2794)
			(end 0.12065 -0.3048)
			(stroke
				(width 0.1)
				(type default)
			)
			(layer "F.Fab")
		)
		(fp_line
			(start 0.12065 -0.3048)
			(end 0.67945 -0.3048)
			(stroke
				(width 0.1)
				(type default)
			)
			(layer "F.Fab")
		)
		(fp_line
			(start 0.120396 0.3048)
			(end 0.120396 0.2794)
			(stroke
				(width 0.1)
				(type default)
			)
			(layer "F.Fab")
		)
		(fp_line
			(start 0.120396 0.2794)
			(end -0.12065 0.2794)
			(stroke
				(width 0.1)
				(type default)
			)
			(layer "F.Fab")
		)
		(fp_line
			(start -0.12065 0.3048)
			(end -0.67945 0.3048)
			(stroke
				(width 0.1)
				(type default)
			)
			(layer "F.Fab")
		)
		(fp_line
			(start -0.12065 0.2794)
			(end -0.12065 0.3048)
			(stroke
				(width 0.1)
				(type default)
			)
			(layer "F.Fab")
		)
		(fp_line
			(start -0.12065 -0.2794)
			(end 0.12065 -0.2794)
			(stroke
				(width 0.1)
				(type default)
			)
			(layer "F.Fab")
		)
		(fp_line
			(start -0.12065 -0.305054)
			(end -0.12065 -0.2794)
			(stroke
				(width 0.1)
				(type default)
			)
			(layer "F.Fab")
		)
		(fp_line
			(start -0.67945 0.3048)
			(end -0.67945 -0.305054)
			(stroke
				(width 0.1)
				(type default)
			)
			(layer "F.Fab")
		)
		(fp_line
			(start -0.67945 -0.305054)
			(end -0.12065 -0.305054)
			(stroke
				(width 0.1)
				(type default)
			)
			(layer "F.Fab")
		)
		(pad "1" smd circle
			(at -0.40005 0 180)
			(size 0 0)
			(layers "F.Cu" "F.Mask" "F.Paste")
			(net "P3V3_E1S_PWRGD_0_R1")
		)
		(pad "2" smd circle
			(at 0.40005 0 180)
			(size 0 0)
			(layers "F.Cu" "F.Mask" "F.Paste")
			(net "GND")
		)
	)
	(footprint ""
		(layer "F.Cu")
		(at 190.881 -100.294948 90)
		(property "Reference" "R263"
			(at 0 0 90)
			(layer "F.SilkS")
			(hide yes)
			(effects
				(font
					(size 1.27 1.27)
				)
			)
		)
		(property "Value" ""
			(at 0 0 90)
			(layer "F.Fab")
			(effects
				(font
					(size 1.27 1.27)
				)
			)
		)
		(duplicate_pad_numbers_are_jumpers no)
		(fp_line
			(start 0.7874 -0.4064)
			(end 0.7874 0.4064)
			(stroke
				(width 0.1524)
				(type default)
			)
			(layer "F.SilkS")
		)
		(fp_line
			(start -0.7874 -0.4064)
			(end 0.7874 -0.4064)
			(stroke
				(width 0.1524)
				(type default)
			)
			(layer "F.SilkS")
		)
		(fp_line
			(start 0.7874 0.4064)
			(end -0.7874 0.4064)
			(stroke
				(width 0.1524)
				(type default)
			)
			(layer "F.SilkS")
		)
		(fp_line
			(start -0.7874 0.4064)
			(end -0.7874 -0.4064)
			(stroke
				(width 0.1524)
				(type default)
			)
			(layer "F.SilkS")
		)
		(fp_line
			(start -0.12065 -0.305054)
			(end -0.12065 -0.2794)
			(stroke
				(width 0.1)
				(type default)
			)
			(layer "F.Fab")
		)
		(fp_line
			(start -0.67945 -0.305054)
			(end -0.12065 -0.305054)
			(stroke
				(width 0.1)
				(type default)
			)
			(layer "F.Fab")
		)
		(fp_line
			(start 0.67945 -0.3048)
			(end 0.67945 0.3048)
			(stroke
				(width 0.1)
				(type default)
			)
			(layer "F.Fab")
		)
		(fp_line
			(start 0.12065 -0.3048)
			(end 0.67945 -0.3048)
			(stroke
				(width 0.1)
				(type default)
			)
			(layer "F.Fab")
		)
		(fp_line
			(start 0.12065 -0.2794)
			(end 0.12065 -0.3048)
			(stroke
				(width 0.1)
				(type default)
			)
			(layer "F.Fab")
		)
		(fp_line
			(start -0.12065 -0.2794)
			(end 0.12065 -0.2794)
			(stroke
				(width 0.1)
				(type default)
			)
			(layer "F.Fab")
		)
		(fp_line
			(start 0.120396 0.2794)
			(end -0.12065 0.2794)
			(stroke
				(width 0.1)
				(type default)
			)
			(layer "F.Fab")
		)
		(fp_line
			(start -0.12065 0.2794)
			(end -0.12065 0.3048)
			(stroke
				(width 0.1)
				(type default)
			)
			(layer "F.Fab")
		)
		(fp_line
			(start 0.67945 0.3048)
			(end 0.120396 0.3048)
			(stroke
				(width 0.1)
				(type default)
			)
			(layer "F.Fab")
		)
		(fp_line
			(start 0.120396 0.3048)
			(end 0.120396 0.2794)
			(stroke
				(width 0.1)
				(type default)
			)
			(layer "F.Fab")
		)
		(fp_line
			(start -0.12065 0.3048)
			(end -0.67945 0.3048)
			(stroke
				(width 0.1)
				(type default)
			)
			(layer "F.Fab")
		)
		(fp_line
			(start -0.67945 0.3048)
			(end -0.67945 -0.305054)
			(stroke
				(width 0.1)
				(type default)
			)
			(layer "F.Fab")
		)
		(pad "1" smd circle
			(at -0.40005 0 90)
			(size 0 0)
			(layers "F.Cu" "F.Mask" "F.Paste")
			(net "CPU1_CORETYPE1")
		)
		(pad "2" smd circle
			(at 0.40005 0 90)
			(size 0 0)
			(layers "F.Cu" "F.Mask" "F.Paste")
			(net "FM_CPU1_CORETYPE1")
		)
	)
)
